FILE_TYPE = CONNECTIVITY;
{Allegro Design Entry HDL 16.6-p007 (v16-6-112F) 10/10/2012}
"PAGE_NUMBER" = 133;
0"NC";
1"GND\g";
2"P3V3_STBY\g";
3"P3V3_STBY\g";
4"P3V3_STBY\g";
5"P3V3_STBY\g";
6"P3V3_STBY\g";
7"P3V3_STBY\g";
8"P3V3_STBY\g";
9"P3V3_STBY\g";
10"P1V05_PCH_STBY\g";
11"P3V3_STBY\g";
12"P3V3_STBY\g";
13"FM_XRC_READY_N";
14"FM_OCP_MEZZA_PRES";
15"FM_TPM_PRES_N";
16"FM_BMC_READY_N";
17"FM_PRSNT_2_1_N";
18"FM_OCP_MEZZC_PRES_1V05_PCH_N";
19"FM_PRSNT_2_2_N";
20"FM_PRSNT_2_3_N";
21"FM_PRSNT_2_4_N";
22"FM_PRSNT_2_5_N";
23"FM_PRSNT_2_6_N";
24"FM_OCP_MEZZB_PRES_1V05_PCH_N";
25"FM_CPU0_RC_ERROR_N";
26"IRQ_BOARD_BMC_ALERT_N";
27"PU_10GBE_LOM_PCI_DISABLE_N";
28"FP_PWR_ID_LED_N";
29"FM_CPU0_RC_EN";
30"FM_BIOS_SMI_ACTIVE_N";
31"IRQ_PCH_NIC_ALERT_N";
32"PWRGD_PCH_PWROK";
33"PWRGD_SYS_PWROK";
34"FM_XRC_PRESENT_N";
35"IRQ_HSC_FAULT_N";
36"FM_PCH_PLD_DATA";
37"FM_SLT_CFG0";
38"IRQ_BMC_PCH_SMI_LPC_N";
39"FM_THROTTLE_N";
40"FM_CPU1_RC_EN";
41"IRQ_BMC_PCH_SCI_LPC_N";
42"FM_BIOS_POST_CMPLT_N";
43"PU_IRQ_VRALERT_N";
44"PU_IRQ_PCH_SCI_WHEA_N";
45"PU_LPC_PME_N";
46"IRQ_PIRQA_SPI_TPM_N";
47"PU_FM_RCIN_N";
48"IRQ_LPC_SERIRQ_N";
49"PU_LPC_CLKRUN_N";
50"FM_WBG_PRSNT_N";
51"FM_SINT_PRSNT_N";
52"FM_PCH_PRSNT_N";
53"FM_CPU1_RC_ERROR_N";
54"FM_SLT_CFG1";
%"GND"
"1","(-2825,3600)","0","mstr_symbols","I110";
;
SIZE"1B"
CDS_LIB"mstr_symbols"
BOM_COST"SB"
VOLTAGE"0"
BODY_TYPE"PLUMBING"
HDL_POWER"GND";
"A\NAC"1;
%"RES"
"1","(-2500,3850)","0","mstr_discrete","I120";
;
WATTAGE"1/16W"
LOCATION"R3N3"
PACK_TYPE"0402"
TOLERANCE"1%"
MATERIAL"CHIP"
VALUE"2.0K"
PART_NUMBER"G21796-001"
CDS_LOCATION"R3N3"
BOM_COST"SB"
ROOM"SB"
CDS_LIB"mstr_discrete"
$SEC"1"
CDS_SEC"1";
"B"
$PN"2"32;
"A"
$PN"1"1;
%"RES"
"1","(-2500,4075)","0","mstr_discrete","I122";
;
VALUE"10.0K"
TOLERANCE"1%"
PACK_TYPE"0402"
LOCATION"R2N12"
PART_NUMBER"G21796-016"
WATTAGE"1/16W"
MATERIAL"EMPTY"
BOM_COST"SB"
ROOM"SB"
CDS_LIB"mstr_discrete"
CDS_LOCATION"R2N12"
CDS_SEC"1"
$SEC"1";
"B"
$PN"2"33;
"A"
$PN"1"1;
%"RES"
"1","(-4700,4500)","0","mstr_discrete","I200";
;
CDS_SEC"1"
VALUE"10.0K"
TOLERANCE"1%"
PACK_TYPE"0402"
PART_NUMBER"G21796-016"
WATTAGE"1/16W"
LOCATION"R7D8"
MATERIAL"CHIP"
CDS_LOCATION"R7D8"
CDS_LIB"mstr_discrete"
ROOM"SB"
SEC_TYPE"0402"
SEC"1";
"B"
$PN"2"49;
"A"
$PN"1"8;
%"RES"
"1","(-4700,4325)","0","mstr_discrete","I202";
;
CDS_SEC"1"
LOCATION"R7D10"
VALUE"10.0K"
TOLERANCE"1%"
PART_NUMBER"G21796-016"
PACK_TYPE"0402"
MATERIAL"CHIP"
WATTAGE"1/16W"
CDS_LIB"mstr_discrete"
CDS_LOCATION"R7D10"
SEC"1"
SEC_TYPE"0402"
ROOM"SB";
"B"
$PN"2"45;
"A"
$PN"1"8;
%"RES"
"1","(-4700,3925)","0","mstr_discrete","I237";
;
CDS_SEC"1"
LOCATION"R7D12"
PACK_TYPE"0402"
MATERIAL"CHIP"
VALUE"10.0K"
TOLERANCE"1%"
WATTAGE"1/16W"
PART_NUMBER"G21796-016"
CDS_LOCATION"R7D12"
CDS_LIB"mstr_discrete"
ROOM"SB"
SEC_TYPE"0402"
SEC"1";
"B"
$PN"2"14;
"A"
$PN"1"8;
%"RES"
"1","(-4700,4900)","0","mstr_discrete","I243";
;
CDS_SEC"1"
PACK_TYPE"0402"
VALUE"4.75K"
PART_NUMBER"G21796-072"
MATERIAL"CHIP"
TOLERANCE"1%"
LOCATION"R7D3"
WATTAGE"1/16W"
ROOM"SB"
CDS_LOCATION"R7D3"
CDS_LIB"mstr_discrete"
SEC_TYPE"0402"
SEC"1";
"B"
$PN"2"48;
"A"
$PN"1"8;
%"RES"
"1","(-4700,4125)","0","mstr_discrete","I245";
;
CDS_SEC"1"
LOCATION"R7D4"
VALUE"10.0K"
TOLERANCE"1%"
WATTAGE"1/16W"
MATERIAL"CHIP"
PACK_TYPE"0402"
PART_NUMBER"G21796-016"
ROOM"SB"
CDS_LOCATION"R7D4"
CDS_LIB"mstr_discrete"
SEC_TYPE"0402"
SEC"1";
"B"
$PN"2"44;
"A"
$PN"1"8;
%"RES"
"1","(-4650,2725)","0","mstr_discrete","I247";
;
WATTAGE"1/16W"
VALUE"10.0K"
LOCATION"R2N16"
TOLERANCE"1%"
MATERIAL"CHIP"
PART_NUMBER"G21796-016"
PACK_TYPE"0402"
CDS_LOCATION"R2N16"
ROOM"SB"
CDS_LIB"mstr_discrete"
BOM_COST"SB"
CDS_SEC"1"
$SEC"1";
"B"
$PN"2"43;
"A"
$PN"1"2;
%"P3V3_STBY"
"1","(-4950,2925)","0","mstr_symbols","I251";
;
SIZE"1B"
CDS_LIB"mstr_symbols"
VOLTAGE"3.3V"
BODY_TYPE"PLUMBING"
HDL_POWER"P3V3_STBY";
"G\NAC"2;
%"P3V3_STBY"
"1","(-5075,1975)","0","mstr_symbols","I256";
;
VOLTAGE"3.3V"
CDS_LIB"mstr_symbols"
SIZE"1B"
BODY_TYPE"PLUMBING"
HDL_POWER"P3V3_STBY";
"G\NAC"3;
%"RES"
"1","(-2600,5125)","0","mstr_discrete","I258";
;
CDS_SEC"1"
TOLERANCE"1%"
WATTAGE"1/16W"
LOCATION"R2R5"
PART_NUMBER"G21796-026"
VALUE"1.00K"
PACK_TYPE"0402"
MATERIAL"CHIP"
BOM_COST"SB"
CDS_LOCATION"R2R5"
ROOM"SB"
CDS_LIB"mstr_discrete"
SEC_TYPE"0402"
SEC"1";
"B"
$PN"2"36;
"A"
$PN"1"4;
%"P3V3_STBY"
"1","(-2825,5350)","0","mstr_symbols","I260";
;
VOLTAGE"3.3V"
CDS_LIB"mstr_symbols"
SIZE"1B"
BODY_TYPE"PLUMBING"
HDL_POWER"P3V3_STBY";
"G\NAC"4;
%"RES"
"1","(-2475,1275)","0","mstr_discrete","I267";
;
CDS_SEC"1"
LOCATION"R2N9"
MATERIAL"CHIP"
PACK_TYPE"0402"
PART_NUMBER"G21796-016"
TOLERANCE"1%"
VALUE"10.0K"
WATTAGE"1/16W"
CDS_LIB"mstr_discrete"
SEC_TYPE"0402"
SEC"1"
CDS_LOCATION"R2N9"
ROOM"SB";
"B"
$PN"2"27;
"A"
$PN"1"5;
%"P3V3_STBY"
"1","(-2750,1425)","0","mstr_symbols","I268";
;
VOLTAGE"3.3V"
CDS_LIB"mstr_symbols"
SIZE"1B"
BODY_TYPE"PLUMBING"
HDL_POWER"P3V3_STBY";
"G\NAC"5;
%"RES"
"1","(-2575,4675)","0","mstr_discrete","I280";
;
CDS_SEC"1"
MATERIAL"CHIP"
WATTAGE"1/16W"
PACK_TYPE"0402"
TOLERANCE"1%"
PART_NUMBER"G21796-026"
VALUE"1.00K"
LOCATION"R8B23"
BOM_COST"SB"
CDS_LOCATION"R8B23"
CDS_LIB"mstr_discrete"
ROOM"SB"
SEC"1"
SEC_TYPE"0402";
"B"
$PN"2"34;
"A"
$PN"1"4;
%"RES"
"1","(-2575,4425)","0","mstr_discrete","I282";
;
CDS_SEC"1"
VALUE"1.00K"
LOCATION"R8B30"
TOLERANCE"1%"
PACK_TYPE"0402"
PART_NUMBER"G21796-026"
WATTAGE"1/16W"
MATERIAL"CHIP"
BOM_COST"SB"
CDS_LIB"mstr_discrete"
ROOM"SB"
CDS_LOCATION"R8B30"
SEC"1"
SEC_TYPE"0402";
"B"
$PN"2"13;
"A"
$PN"1"4;
%"RES"
"1","(-2600,4900)","0","mstr_discrete","I284";
;
CDS_SEC"1"
LOCATION"R2M4"
PACK_TYPE"0402"
MATERIAL"CHIP"
VALUE"1.00K"
TOLERANCE"1%"
PART_NUMBER"G21796-026"
WATTAGE"1/16W"
CDS_LOCATION"R2M4"
BOM_COST"SB"
CDS_LIB"mstr_discrete"
ROOM"SB"
SEC_TYPE"0402"
SEC"1";
"B"
$PN"2"35;
"A"
$PN"1"4;
%"RES"
"1","(-4800,950)","0","mstr_discrete","I286";
;
CDS_SEC"1"
VALUE"1.00K"
WATTAGE"1/16W"
TOLERANCE"1%"
PACK_TYPE"0402"
LOCATION"R8C4"
PART_NUMBER"G21796-026"
MATERIAL"CHIP"
CDS_LIB"mstr_discrete"
ROOM"SB"
BOM_COST"SB_PU_PD"
CDS_LOCATION"R8C4"
SEC"1"
SEC_TYPE"0402";
"B"
$PN"2"38;
"A"
$PN"1"3;
%"RES"
"2","(-175,1425)","0","mstr_discrete","I295";
;
CDS_SEC"1"
PACK_TYPE"0402"
MATERIAL"CHIP"
PART_NUMBER"G21796-016"
WATTAGE"1/16W"
TOLERANCE"1%"
VALUE"10.0K"
LOCATION"R7B6"
CDS_LIB"mstr_discrete"
CDS_LOCATION"R7B6"
SEC"1"
SEC_TYPE"0402"
ROOM"SB_PU_PD";
"A"
$PN"1"6;
"B"
$PN"2"52;
%"RES"
"2","(-425,1425)","0","mstr_discrete","I296";
;
CDS_SEC"1"
PACK_TYPE"0402"
MATERIAL"CHIP"
TOLERANCE"1%"
WATTAGE"1/16W"
PART_NUMBER"G21796-016"
VALUE"10.0K"
LOCATION"R7C8"
CDS_LIB"mstr_discrete"
CDS_LOCATION"R7C8"
SEC"1"
SEC_TYPE"0402"
ROOM"SB_PU_PD";
"A"
$PN"1"6;
"B"
$PN"2"50;
%"RES"
"2","(-650,1425)","0","mstr_discrete","I297";
;
CDS_SEC"1"
TOLERANCE"1%"
WATTAGE"1/16W"
LOCATION"R7C5"
PART_NUMBER"G21796-016"
VALUE"10.0K"
PACK_TYPE"0402"
MATERIAL"CHIP"
CDS_LIB"mstr_discrete"
ROOM"SB_PU_PD"
SEC_TYPE"0402"
SEC"1"
CDS_LOCATION"R7C5";
"A"
$PN"1"6;
"B"
$PN"2"51;
%"P3V3_STBY"
"1","(-650,1850)","0","mstr_symbols","I298";
;
VOLTAGE"3.3V"
SIZE"1B"
CDS_LIB"mstr_symbols"
BODY_TYPE"PLUMBING"
HDL_POWER"P3V3_STBY";
"G\NAC"6;
%"P3V3_STBY"
"1","(-2800,2050)","0","mstr_symbols","I300";
;
VOLTAGE"3.3V"
SIZE"1B"
CDS_LIB"mstr_symbols"
BODY_TYPE"PLUMBING"
HDL_POWER"P3V3_STBY";
"G\NAC"7;
%"RES"
"1","(-2475,1800)","0","mstr_discrete","I301";
;
CDS_SEC"1"
VALUE"4.75K"
LOCATION"R8D14"
PART_NUMBER"G21796-072"
WATTAGE"1/16W"
MATERIAL"CHIP"
TOLERANCE"1%"
PACK_TYPE"0402"
BOM_COST"SB"
CDS_LIB"mstr_discrete"
ROOM"SB"
SEC_TYPE"0402"
SEC"1"
CDS_LOCATION"R8D14";
"B"
$PN"2"28;
"A"
$PN"1"7;
%"P3V3_STBY"
"1","(-4950,5225)","0","mstr_symbols","I302";
;
CDS_LIB"mstr_symbols"
SIZE"1B"
VOLTAGE"3.3V"
BODY_TYPE"PLUMBING"
HDL_POWER"P3V3_STBY";
"G\NAC"8;
%"RES"
"1","(-4675,2400)","0","mstr_discrete","I303";
;
CDS_SEC"1"
WATTAGE"1/16W"
PACK_TYPE"0402"
LOCATION"R8C6"
TOLERANCE"1%"
VALUE"4.75K"
PART_NUMBER"G21796-072"
MATERIAL"CHIP"
CDS_LOCATION"R8C6"
CDS_LIB"mstr_discrete"
ROOM"SB_PU_PD"
SEC"1"
SEC_TYPE"0402";
"B"
$PN"2"42;
"A"
$PN"1"2;
%"RES"
"1","(-4800,1825)","0","mstr_discrete","I304";
;
CDS_SEC"1"
TOLERANCE"1%"
PACK_TYPE"0402"
VALUE"4.75K"
PART_NUMBER"G21796-072"
LOCATION"R8C2"
MATERIAL"CHIP"
WATTAGE"1/16W"
CDS_LOCATION"R8C2"
CDS_LIB"mstr_discrete"
ROOM"SB_PU_PD"
SEC_TYPE"0402"
SEC"1";
"B"
$PN"2"41;
"A"
$PN"1"3;
%"RES"
"1","(-4700,3700)","0","mstr_discrete","I306";
;
CDS_SEC"1"
LOCATION"R7D6"
VALUE"4.75K"
TOLERANCE"1%"
PACK_TYPE"0402"
WATTAGE"1/16W"
MATERIAL"CHIP"
PART_NUMBER"G21796-072"
SEC_TYPE"0402"
SEC"1"
ROOM"SB_PU_PD"
CDS_LIB"mstr_discrete"
CDS_LOCATION"R7D6";
"B"
$PN"2"16;
"A"
$PN"1"8;
%"RES"
"1","(-4800,1650)","0","mstr_discrete","I307";
;
CDS_SEC"1"
TOLERANCE"1%"
WATTAGE"1/16W"
VALUE"4.75K"
LOCATION"R8B31"
PACK_TYPE"0402"
MATERIAL"CHIP"
PART_NUMBER"G21796-072"
CDS_LOCATION"R8B31"
CDS_LIB"mstr_discrete"
ROOM"SB_PU_PD"
SEC"1"
SEC_TYPE"0402";
"B"
$PN"2"39;
"A"
$PN"1"3;
%"RES"
"1","(-2475,1025)","0","mstr_discrete","I309";
;
CDS_SEC"1"
TOLERANCE"1%"
VALUE"4.75K"
MATERIAL"CHIP"
PART_NUMBER"G21796-072"
WATTAGE"1/16W"
PACK_TYPE"0402"
LOCATION"R2N7"
CDS_LOCATION"R2N7"
SEC"1"
CDS_LIB"mstr_discrete"
SEC_TYPE"0402"
ROOM"SB_PU_PD";
"B"
$PN"2"26;
"A"
$PN"1"5;
%"RES"
"1","(-375,3925)","0","mstr_discrete","I322";
;
CDS_SEC"1"
TOLERANCE"1%"
VALUE"1.00K"
LOCATION"R3P8"
PART_NUMBER"G21796-026"
WATTAGE"1/16W"
MATERIAL"CHIP"
PACK_TYPE"0402"
BOM_COST"SB"
CDS_LOCATION"R3P8"
CDS_LIB"mstr_discrete"
ROOM"SB"
SEC"1"
SEC_TYPE"0402";
"B"
$PN"2"23;
"A"
$PN"1"10;
%"RES"
"1","(-4800,1300)","0","mstr_discrete","I326";
;
CDS_SEC"1"
TOLERANCE"1%"
PACK_TYPE"0402"
MATERIAL"CHIP"
WATTAGE"1/16W"
VALUE"4.75K"
LOCATION"R8C1"
PART_NUMBER"G21796-072"
CDS_LOCATION"R8C1"
CDS_LIB"mstr_discrete"
ROOM"SB_PU_PD"
SEC"1"
SEC_TYPE"0402";
"B"
$PN"2"54;
"A"
$PN"1"3;
%"RES"
"1","(-4800,1125)","0","mstr_discrete","I327";
;
CDS_SEC"1"
VALUE"4.75K"
WATTAGE"1/16W"
LOCATION"R8C7"
TOLERANCE"1%"
MATERIAL"CHIP"
PACK_TYPE"0402"
PART_NUMBER"G21796-072"
BOM_COST"SB"
CDS_LOCATION"R8C7"
CDS_LIB"mstr_discrete"
ROOM"SB_PU_PD"
SEC_TYPE"0402"
SEC"1";
"B"
$PN"2"37;
"A"
$PN"1"3;
%"RES"
"1","(-4700,4700)","0","mstr_discrete","I331";
;
CDS_SEC"1"
PACK_TYPE"0402"
MATERIAL"CHIP"
PART_NUMBER"G21796-026"
TOLERANCE"1%"
VALUE"1.00K"
LOCATION"R7D7"
WATTAGE"1/16W"
BOM_COST"SB_PU_PD"
CDS_LOCATION"R7D7"
CDS_LIB"mstr_discrete"
ROOM"SB"
SEC_TYPE"0402"
SEC"1";
"B"
$PN"2"46;
"A"
$PN"1"8;
%"RES"
"1","(-4700,5100)","0","mstr_discrete","I332";
;
CDS_SEC"1"
PART_NUMBER"G21796-026"
PACK_TYPE"0402"
MATERIAL"CHIP"
LOCATION"R7D2"
WATTAGE"1/16W"
VALUE"1.00K"
TOLERANCE"1%"
BOM_COST"SB_PU_PD"
ROOM"SB"
CDS_LIB"mstr_discrete"
CDS_LOCATION"R7D2"
SEC"1"
SEC_TYPE"0402";
"B"
$PN"2"47;
"A"
$PN"1"8;
%"RES"
"1","(-2500,3150)","0","mstr_discrete","I333";
;
CDS_SEC"1"
PACK_TYPE"0402"
VALUE"4.75K"
LOCATION"R8C25"
WATTAGE"1/16W"
TOLERANCE"1%"
PART_NUMBER"G21796-072"
MATERIAL"CHIP"
CDS_LOCATION"R8C25"
ROOM"SB_PU_PD"
CDS_LIB"mstr_discrete"
SEC_TYPE"0402"
SEC"1";
"B"
$PN"2"31;
"A"
$PN"1"9;
%"P3V3_STBY"
"1","(-2775,3425)","0","mstr_symbols","I335";
;
VOLTAGE"3.3V"
CDS_LIB"mstr_symbols"
SIZE"1B"
BODY_TYPE"PLUMBING"
HDL_POWER"P3V3_STBY";
"G\NAC"9;
%"P1V05_PCH_STBY"
"1","(-625,5325)","0","mstr_symbols","I339";
;
CDS_LIB"mstr_symbols"
VOLTAGE"1.05V"
BODY_TYPE"PLUMBING"
HDL_POWER"P1V05_PCH_STBY";
"G\NAC"10;
%"RES"
"1","(-2475,2700)","0","mstr_discrete","I341";
;
CDS_SEC"1"
CDS_LOCATION"R2N32"
LOCATION"R2N32"
PART_NUMBER"G21796-072"
PACK_TYPE"0402"
WATTAGE"1/16W"
VALUE"4.75K"
TOLERANCE"1%"
MATERIAL"CHIP"
BOM_COST"SB"
CDS_LIB"mstr_discrete"
ROOM"SB"
SEC"1"
SEC_TYPE"0402";
"B"
$PN"2"30;
"A"
$PN"1"11;
%"P3V3_STBY"
"1","(-2800,2875)","0","mstr_symbols","I342";
;
VOLTAGE"3.3V"
CDS_LIB"mstr_symbols"
SIZE"1B"
BODY_TYPE"PLUMBING"
HDL_POWER"P3V3_STBY";
"G\NAC"11;
%"RES"
"1","(-375,2725)","0","mstr_discrete","I349";
;
CDS_SEC"1"
CDS_LOCATION"R2M8"
VALUE"1.5K"
TOLERANCE"1%"
PART_NUMBER"G21796-003"
MATERIAL"CHIP"
WATTAGE"1/16W"
PACK_TYPE"0402"
LOCATION"R2M8"
BOM_COST"SB"
CDS_LIB"mstr_discrete"
ROOM"SB"
SEC"1"
SEC_TYPE"0402";
"B"
$PN"2"25;
"A"
$PN"1"12;
%"RES"
"1","(-375,2475)","0","mstr_discrete","I352";
;
CDS_SEC"1"
CDS_LOCATION"R2N29"
TOLERANCE"1%"
LOCATION"R2N29"
PART_NUMBER"G21796-003"
MATERIAL"CHIP"
PACK_TYPE"0402"
VALUE"1.5K"
WATTAGE"1/16W"
BOM_COST"SB"
CDS_LIB"mstr_discrete"
ROOM"SB"
SEC"1"
SEC_TYPE"0402";
"B"
$PN"2"53;
"A"
$PN"1"12;
%"P3V3_STBY"
"1","(-625,2950)","0","mstr_symbols","I353";
;
CDS_LIB"mstr_symbols"
SIZE"1B"
VOLTAGE"3.3V"
BODY_TYPE"PLUMBING"
HDL_POWER"P3V3_STBY";
"G\NAC"12;
%"RES"
"1","(-375,3725)","0","mstr_discrete","I356";
;
CDS_SEC"1"
CDS_LOCATION"R7D44"
VALUE"4.75K"
MATERIAL"CHIP"
TOLERANCE"1%"
WATTAGE"1/16W"
PART_NUMBER"G21796-072"
PACK_TYPE"0402"
LOCATION"R7D44"
ROOM"SB_PU_PD"
SEC_TYPE"0402"
SEC"1"
CDS_LIB"mstr_discrete";
"B"
$PN"2"24;
"A"
$PN"1"10;
%"RES"
"1","(-4800,1500)","0","mstr_discrete","I360";
;
CDS_SEC"1"
CDS_LOCATION"R2P22"
WATTAGE"1/16W"
VALUE"10.0K"
PART_NUMBER"G21796-016"
LOCATION"R2P22"
PACK_TYPE"0402"
TOLERANCE"1%"
MATERIAL"CHIP"
BOM_COST"SB"
ROOM"SB"
CDS_LIB"mstr_discrete"
SEC"1"
SEC_TYPE"0402";
"B"
$PN"2"40;
"A"
$PN"1"3;
%"RES"
"1","(-2475,2450)","0","mstr_discrete","I362";
;
CDS_SEC"1"
CDS_LOCATION"R8D44"
LOCATION"R8D44"
PART_NUMBER"G21796-016"
TOLERANCE"1%"
WATTAGE"1/16W"
VALUE"10.0K"
MATERIAL"CHIP"
PACK_TYPE"0402"
BOM_COST"SB"
CDS_LIB"mstr_discrete"
ROOM"SB"
SEC"1"
SEC_TYPE"0402";
"B"
$PN"2"29;
"A"
$PN"1"11;
%"RES"
"1","(-375,3525)","0","mstr_discrete","I365";
;
CDS_SEC"1"
$SEC"1"
CDS_LOCATION"R3P53"
TOLERANCE"1%"
MATERIAL"CHIP"
PART_NUMBER"G21796-072"
PACK_TYPE"0402"
WATTAGE"1/16W"
VALUE"4.75K"
LOCATION"R3P53"
CDS_LIB"mstr_discrete"
ROOM"SB_PU_PD";
"B"
$PN"2"18;
"A"
$PN"1"10;
%"RES"
"2","(-400,4875)","3","mstr_discrete","I366";
;
PART_NUMBER"G21796-026"
MATERIAL"EMPTY"
WATTAGE"1/16W"
VALUE"1.00K"
PACK_TYPE"0402"
TOLERANCE"1%"
LOCATION"R3P5"
CDS_LOCATION"R3P5"
CDS_SEC"1"
CDS_LIB"mstr_discrete"
ROOM"DEBUG"
SEC"1"
SEC_TYPE"0402";
"A"
$PN"1"10;
"B"
$PN"2"19;
%"RES"
"2","(-375,4650)","3","mstr_discrete","I367";
;
TOLERANCE"1%"
WATTAGE"1/16W"
PART_NUMBER"G21796-026"
VALUE"1.00K"
MATERIAL"EMPTY"
PACK_TYPE"0402"
LOCATION"R3P6"
SEC_TYPE"0402"
SEC"1"
ROOM"DEBUG"
CDS_LIB"mstr_discrete"
CDS_SEC"1"
CDS_LOCATION"R3P6";
"A"
$PN"1"10;
"B"
$PN"2"20;
%"RES"
"2","(-375,4400)","3","mstr_discrete","I368";
;
TOLERANCE"1%"
VALUE"1.00K"
LOCATION"R3N15"
WATTAGE"1/16W"
MATERIAL"EMPTY"
PACK_TYPE"0402"
PART_NUMBER"G21796-026"
SEC_TYPE"0402"
SEC"1"
ROOM"DEBUG"
CDS_LIB"mstr_discrete"
CDS_SEC"1"
CDS_LOCATION"R3N15";
"A"
$PN"1"10;
"B"
$PN"2"21;
%"RES"
"2","(-375,4175)","3","mstr_discrete","I369";
;
TOLERANCE"1%"
MATERIAL"EMPTY"
WATTAGE"1/16W"
VALUE"1.00K"
PACK_TYPE"0402"
PART_NUMBER"G21796-026"
LOCATION"R3N16"
SEC_TYPE"0402"
SEC"1"
ROOM"DEBUG"
CDS_LIB"mstr_discrete"
CDS_SEC"1"
CDS_LOCATION"R3N16";
"A"
$PN"1"10;
"B"
$PN"2"22;
%"RES"
"2","(-400,5100)","3","mstr_discrete","I370";
;
MATERIAL"EMPTY"
WATTAGE"1/16W"
VALUE"1.00K"
TOLERANCE"1%"
LOCATION"R3P7"
PART_NUMBER"G21796-026"
PACK_TYPE"0402"
CDS_SEC"1"
CDS_LIB"mstr_discrete"
ROOM"DEBUG"
SEC"1"
SEC_TYPE"0402"
CDS_LOCATION"R3P7";
"A"
$PN"1"10;
"B"
$PN"2"17;
%"RES"
"1","(-4700,3475)","0","mstr_discrete","I371";
;
CDS_SEC"1"
VALUE"4.75K"
WATTAGE"1/16W"
TOLERANCE"1%"
MATERIAL"CHIP"
PART_NUMBER"G21796-072"
LOCATION"R8E3"
PACK_TYPE"0402"
SEC_TYPE"0402"
SEC"1"
ROOM"SB_PU_PD"
CDS_LIB"mstr_discrete"
CDS_LOCATION"R8E3";
"B"
$PN"2"15;
"A"
$PN"1"8;
END.
